(kicad_pcb
	(version 20260206)
	(generator "pcbnew")
	(generator_version "10.0")
	(general
		(thickness 1.6)
		(legacy_teardrops no)
	)
	(paper "A4")
	(title_block
		(title "baseboard — 13948-1b.1110WZS1818.brd")
		(comment 1 "Honey Badger (Wiwynn) / footprints 2080-2087 of 2523")
	)
	(layers
		(0 "F.Cu" signal "TOP")
		(4 "In1.Cu" signal "L2GND")
		(6 "In2.Cu" signal "L3")
		(8 "In3.Cu" signal "L4VCC")
		(10 "In4.Cu" signal "L5VCC")
		(12 "In5.Cu" signal "L6")
		(14 "In6.Cu" signal "L7GND")
		(2 "B.Cu" signal "BOTTOM")
		(9 "F.Adhes" user "F.Adhesive")
		(11 "B.Adhes" user "B.Adhesive")
		(13 "F.Paste" user "Package Geometry/Pastemask Top")
		(15 "B.Paste" user "Package Geometry/Pastemask Bottom")
		(5 "F.SilkS" user "Ref Des/Silkscreen Top")
		(7 "B.SilkS" user "Ref Des/Silkscreen Bottom")
		(1 "F.Mask" user "Board Geometry/Soldermask Top")
		(3 "B.Mask" user "Board Geometry/Soldermask Bottom")
		(17 "Dwgs.User" user "User.Drawings")
		(19 "Cmts.User" user "User.Comments")
		(21 "Eco1.User" user "User.Eco1")
		(23 "Eco2.User" user "User.Eco2")
		(25 "Edge.Cuts" user "Board Geometry/Outline")
		(27 "Margin" user)
		(31 "F.CrtYd" user "Package Geometry/Place Bound Top")
		(29 "B.CrtYd" user "Package Geometry/Place Bound Bottom")
		(35 "F.Fab" user "Ref Des/Assembly Top")
		(33 "B.Fab" user "Ref Des/Assembly Bottom")
	)
	(footprint ""
		(layer "B.Cu")
		(at 109.982 -94.488 -90)
		(property "Reference" "SC1251"
			(at 0 0 90)
			(layer "B.SilkS")
			(hide yes)
			(effects
				(font
					(size 1.27 1.27)
				)
				(justify mirror)
			)
		)
		(property "Value" "SCD1U6D3V1KX-GP"
			(at 2.8321 -1.7399 270)
			(unlocked yes)
			(layer "B.Fab")
			(hide yes)
			(effects
				(font
					(size 1.016 1.016)
					(thickness 0.1524)
				)
				(justify mirror)
			)
		)
		(property "Device Type" "C0201H13"
			(at 2.8321 -3.2639 270)
			(unlocked yes)
			(layer "B.Fab")
			(hide yes)
			(effects
				(font
					(size 1.016 1.016)
					(thickness 0.1524)
				)
				(justify mirror)
			)
		)
		(duplicate_pad_numbers_are_jumpers no)
		(fp_rect
			(start 0.2794 0.6477)
			(end -0.2794 -0.6477)
			(stroke
				(width 0)
				(type default)
			)
			(fill no)
			(layer "B.CrtYd")
		)
		(fp_rect
			(start 0.2794 0.6477)
			(end -0.2794 -0.6477)
			(stroke
				(width 0)
				(type default)
			)
			(fill no)
			(layer "B.Fab")
		)
		(pad "1" smd custom
			(at 0 -0.2794 90)
			(size 0.0762 0.0762)
			(layers "B.Cu" "B.Mask" "B.Paste")
			(net "P0V9_E")
			(options
				(clearance outline)
				(anchor circle)
			)
			(primitives
				(gr_poly
					(pts
						(arc
							(start 0.1524 0.127)
							(mid 0.137521 0.162921)
							(end 0.1016 0.1778)
						)
						(arc
							(start -0.1016 0.1778)
							(mid -0.137521 0.162921)
							(end -0.1524 0.127)
						)
						(arc
							(start -0.1524 -0.127)
							(mid -0.137521 -0.162921)
							(end -0.1016 -0.1778)
						)
						(arc
							(start 0.1016 -0.1778)
							(mid 0.137521 -0.162921)
							(end 0.1524 -0.127)
						)
					)
					(width 0)
					(fill yes)
				)
			)
		)
		(pad "2" smd custom
			(at 0 0.2794 90)
			(size 0.0762 0.0762)
			(layers "B.Cu" "B.Mask" "B.Paste")
			(net "GND")
			(options
				(clearance outline)
				(anchor circle)
			)
			(primitives
				(gr_poly
					(pts
						(arc
							(start 0.1524 0.127)
							(mid 0.137521 0.162921)
							(end 0.1016 0.1778)
						)
						(arc
							(start -0.1016 0.1778)
							(mid -0.137521 0.162921)
							(end -0.1524 0.127)
						)
						(arc
							(start -0.1524 -0.127)
							(mid -0.137521 -0.162921)
							(end -0.1016 -0.1778)
						)
						(arc
							(start 0.1016 -0.1778)
							(mid 0.137521 -0.162921)
							(end 0.1524 -0.127)
						)
					)
					(width 0)
					(fill yes)
				)
			)
		)
	)
	(footprint ""
		(layer "B.Cu")
		(at 107.169966 -44.958 90)
		(property "Reference" "SC1055"
			(at 0 0 90)
			(layer "B.SilkS")
			(hide yes)
			(effects
				(font
					(size 1.27 1.27)
				)
				(justify mirror)
			)
		)
		(property "Value" "SCD1U16V2KX-3GP"
			(at -1.1811 -2.7051 90)
			(unlocked yes)
			(layer "B.Fab")
			(hide yes)
			(effects
				(font
					(size 1.016 1.016)
					(thickness 0.1524)
				)
				(justify mirror)
			)
		)
		(property "Device Type" "C402H22"
			(at -1.1811 -4.2291 90)
			(unlocked yes)
			(layer "B.Fab")
			(hide yes)
			(effects
				(font
					(size 1.016 1.016)
					(thickness 0.1524)
				)
				(justify mirror)
			)
		)
		(duplicate_pad_numbers_are_jumpers no)
		(fp_rect
			(start 0.4318 0.9525)
			(end -0.4318 -0.9525)
			(stroke
				(width 0)
				(type default)
			)
			(fill no)
			(layer "B.CrtYd")
		)
		(fp_rect
			(start 0.4318 0.9525)
			(end -0.4318 -0.9525)
			(stroke
				(width 0)
				(type default)
			)
			(fill no)
			(layer "B.Fab")
		)
		(pad "1" smd custom
			(at 0 -0.4445 270)
			(size 0.1524 0.1524)
			(layers "B.Cu" "B.Mask" "B.Paste")
			(net "P0V955_C")
			(options
				(clearance outline)
				(anchor circle)
			)
			(primitives
				(gr_poly
					(pts
						(arc
							(start 0.3048 0.2032)
							(mid 0.275042 0.275042)
							(end 0.2032 0.3048)
						)
						(arc
							(start -0.2032 0.3048)
							(mid -0.275042 0.275042)
							(end -0.3048 0.2032)
						)
						(arc
							(start -0.3048 -0.2032)
							(mid -0.275042 -0.275042)
							(end -0.2032 -0.3048)
						)
						(arc
							(start 0.2032 -0.3048)
							(mid 0.275042 -0.275042)
							(end 0.3048 -0.2032)
						)
					)
					(width 0)
					(fill yes)
				)
			)
		)
		(pad "2" smd custom
			(at 0 0.4445 270)
			(size 0.1524 0.1524)
			(layers "B.Cu" "B.Mask" "B.Paste")
			(net "GND")
			(options
				(clearance outline)
				(anchor circle)
			)
			(primitives
				(gr_poly
					(pts
						(arc
							(start 0.3048 0.2032)
							(mid 0.275042 0.275042)
							(end 0.2032 0.3048)
						)
						(arc
							(start -0.2032 0.3048)
							(mid -0.275042 0.275042)
							(end -0.3048 0.2032)
						)
						(arc
							(start -0.3048 -0.2032)
							(mid -0.275042 -0.275042)
							(end -0.2032 -0.3048)
						)
						(arc
							(start 0.2032 -0.3048)
							(mid 0.275042 -0.275042)
							(end 0.3048 -0.2032)
						)
					)
					(width 0)
					(fill yes)
				)
			)
		)
	)
	(footprint ""
		(layer "B.Cu")
		(at 109.728 -92.964)
		(property "Reference" "STP162"
			(at 0 0 0)
			(layer "B.SilkS")
			(hide yes)
			(effects
				(font
					(size 1.27 1.27)
				)
				(justify mirror)
			)
		)
		(property "Value" "TPAD28"
			(at -0.0127 -1.8034 0)
			(unlocked yes)
			(layer "B.Fab")
			(hide yes)
			(effects
				(font
					(size 1.016 1.016)
					(thickness 0.1524)
				)
				(justify mirror)
			)
		)
		(property "Device Type" "TPAD28"
			(at -0.0127 -3.3274 0)
			(unlocked yes)
			(layer "B.Fab")
			(hide yes)
			(effects
				(font
					(size 1.016 1.016)
					(thickness 0.1524)
				)
				(justify mirror)
			)
		)
		(duplicate_pad_numbers_are_jumpers no)
		(fp_poly
			(pts
				(arc
					(start 0.3556 0)
					(mid -0.3556 0)
					(end 0.3556 0)
				)
			)
			(stroke
				(width 0)
				(type default)
			)
			(fill no)
			(layer "B.CrtYd")
		)
		(fp_poly
			(pts
				(arc
					(start 0.6096 0)
					(mid -0.6096 0)
					(end 0.6096 0)
				)
			)
			(stroke
				(width 0)
				(type default)
			)
			(fill no)
			(layer "B.Fab")
		)
		(pad "1" smd circle
			(at 0 0 180)
			(size 0.7112 0.7112)
			(layers "B.Cu" "B.Mask" "B.Paste")
			(net "EXP_XM_ADDR_24")
		)
	)
	(footprint ""
		(layer "B.Cu")
		(at 89.67216 -53.086)
		(property "Reference" "SR633"
			(at 0 0 0)
			(layer "B.SilkS")
			(hide yes)
			(effects
				(font
					(size 1.27 1.27)
				)
				(justify mirror)
			)
		)
		(property "Value" "2K2R2F-GP"
			(at -0.064008 -3.993896 0)
			(unlocked yes)
			(layer "B.Fab")
			(hide yes)
			(effects
				(font
					(size 1.016 1.016)
					(thickness 0.1524)
				)
				(justify mirror)
			)
		)
		(property "Device Type" "R402H16"
			(at -0.064008 -5.517896 0)
			(unlocked yes)
			(layer "B.Fab")
			(hide yes)
			(effects
				(font
					(size 1.016 1.016)
					(thickness 0.1524)
				)
				(justify mirror)
			)
		)
		(duplicate_pad_numbers_are_jumpers no)
		(fp_line
			(start -0.508 -0.9398)
			(end 0.508 -0.9398)
			(stroke
				(width 0.1524)
				(type default)
			)
			(layer "B.SilkS")
		)
		(fp_line
			(start 0.508 -0.9398)
			(end 0.508 0.9398)
			(stroke
				(width 0.1524)
				(type default)
			)
			(layer "B.SilkS")
		)
		(fp_rect
			(start 0.508 0.9398)
			(end -0.508 -0.9398)
			(stroke
				(width 0)
				(type default)
			)
			(fill no)
			(layer "B.CrtYd")
		)
		(fp_rect
			(start 0.508 0.9398)
			(end -0.508 -0.9398)
			(stroke
				(width 0)
				(type default)
			)
			(fill no)
			(layer "B.Fab")
		)
		(pad "1" smd custom
			(at 0 -0.4445 180)
			(size 0.1397 0.1397)
			(layers "B.Cu" "B.Mask" "B.Paste")
			(net "P1V8_C")
			(options
				(clearance outline)
				(anchor circle)
			)
			(primitives
				(gr_poly
					(pts
						(arc
							(start -0.1778 0.2794)
							(mid -0.249642 0.249642)
							(end -0.2794 0.1778)
						)
						(arc
							(start -0.2794 -0.1778)
							(mid -0.249642 -0.249642)
							(end -0.1778 -0.2794)
						)
						(arc
							(start 0.1778 -0.2794)
							(mid 0.249642 -0.249642)
							(end 0.2794 -0.1778)
						)
						(arc
							(start 0.2794 0.1778)
							(mid 0.249642 0.249642)
							(end 0.1778 0.2794)
						)
					)
					(width 0)
					(fill yes)
				)
			)
		)
		(pad "2" smd custom
			(at 0 0.4445 180)
			(size 0.1397 0.1397)
			(layers "B.Cu" "B.Mask" "B.Paste")
			(net "SIO_LOAD_1")
			(options
				(clearance outline)
				(anchor circle)
			)
			(primitives
				(gr_poly
					(pts
						(arc
							(start -0.1778 0.2794)
							(mid -0.249642 0.249642)
							(end -0.2794 0.1778)
						)
						(arc
							(start -0.2794 -0.1778)
							(mid -0.249642 -0.249642)
							(end -0.1778 -0.2794)
						)
						(arc
							(start 0.1778 -0.2794)
							(mid 0.249642 -0.249642)
							(end 0.2794 -0.1778)
						)
						(arc
							(start 0.2794 0.1778)
							(mid 0.249642 0.249642)
							(end 0.1778 0.2794)
						)
					)
					(width 0)
					(fill yes)
				)
			)
		)
	)
	(footprint ""
		(layer "B.Cu")
		(at 105.290366 -41.91 90)
		(property "Reference" "SC1032"
			(at 0 0 90)
			(layer "B.SilkS")
			(hide yes)
			(effects
				(font
					(size 1.27 1.27)
				)
				(justify mirror)
			)
		)
		(property "Value" "SC1KP50V2KX-1GP"
			(at -1.1811 -2.7051 90)
			(unlocked yes)
			(layer "B.Fab")
			(hide yes)
			(effects
				(font
					(size 1.016 1.016)
					(thickness 0.1524)
				)
				(justify mirror)
			)
		)
		(property "Device Type" "C402H22"
			(at -1.1811 -4.2291 90)
			(unlocked yes)
			(layer "B.Fab")
			(hide yes)
			(effects
				(font
					(size 1.016 1.016)
					(thickness 0.1524)
				)
				(justify mirror)
			)
		)
		(duplicate_pad_numbers_are_jumpers no)
		(fp_rect
			(start 0.4318 0.9525)
			(end -0.4318 -0.9525)
			(stroke
				(width 0)
				(type default)
			)
			(fill no)
			(layer "B.CrtYd")
		)
		(fp_rect
			(start 0.4318 0.9525)
			(end -0.4318 -0.9525)
			(stroke
				(width 0)
				(type default)
			)
			(fill no)
			(layer "B.Fab")
		)
		(pad "1" smd custom
			(at 0 -0.4445 270)
			(size 0.1524 0.1524)
			(layers "B.Cu" "B.Mask" "B.Paste")
			(net "P0V955_C")
			(options
				(clearance outline)
				(anchor circle)
			)
			(primitives
				(gr_poly
					(pts
						(arc
							(start 0.3048 0.2032)
							(mid 0.275042 0.275042)
							(end 0.2032 0.3048)
						)
						(arc
							(start -0.2032 0.3048)
							(mid -0.275042 0.275042)
							(end -0.3048 0.2032)
						)
						(arc
							(start -0.3048 -0.2032)
							(mid -0.275042 -0.275042)
							(end -0.2032 -0.3048)
						)
						(arc
							(start 0.2032 -0.3048)
							(mid 0.275042 -0.275042)
							(end 0.3048 -0.2032)
						)
					)
					(width 0)
					(fill yes)
				)
			)
		)
		(pad "2" smd custom
			(at 0 0.4445 270)
			(size 0.1524 0.1524)
			(layers "B.Cu" "B.Mask" "B.Paste")
			(net "GND")
			(options
				(clearance outline)
				(anchor circle)
			)
			(primitives
				(gr_poly
					(pts
						(arc
							(start 0.3048 0.2032)
							(mid 0.275042 0.275042)
							(end 0.2032 0.3048)
						)
						(arc
							(start -0.2032 0.3048)
							(mid -0.275042 0.275042)
							(end -0.3048 0.2032)
						)
						(arc
							(start -0.3048 -0.2032)
							(mid -0.275042 -0.275042)
							(end -0.2032 -0.3048)
						)
						(arc
							(start 0.2032 -0.3048)
							(mid 0.275042 -0.275042)
							(end 0.3048 -0.2032)
						)
					)
					(width 0)
					(fill yes)
				)
			)
		)
	)
	(footprint ""
		(layer "B.Cu")
		(at 285.6992 -204.978 180)
		(property "Reference" "C199"
			(at 0 0 0)
			(layer "B.SilkS")
			(hide yes)
			(effects
				(font
					(size 1.27 1.27)
				)
				(justify mirror)
			)
		)
		(property "Value" "SC1U10V3KX-4GP-U"
			(at 0 -2.8194 180)
			(unlocked yes)
			(layer "B.Fab")
			(hide yes)
			(effects
				(font
					(size 1.016 1.016)
					(thickness 0.1524)
				)
				(justify mirror)
			)
		)
		(property "Device Type" "C603H36"
			(at 0 -4.3434 180)
			(unlocked yes)
			(layer "B.Fab")
			(hide yes)
			(effects
				(font
					(size 1.016 1.016)
					(thickness 0.1524)
				)
				(justify mirror)
			)
		)
		(duplicate_pad_numbers_are_jumpers no)
		(fp_line
			(start -0.508 0)
			(end 0.508 0)
			(stroke
				(width 0.2032)
				(type default)
			)
			(layer "B.SilkS")
		)
		(fp_rect
			(start 0.5842 1.3335)
			(end -0.5842 -1.3335)
			(stroke
				(width 0)
				(type default)
			)
			(fill no)
			(layer "B.CrtYd")
		)
		(fp_rect
			(start 0.5842 1.3335)
			(end -0.5842 -1.3335)
			(stroke
				(width 0)
				(type default)
			)
			(fill no)
			(layer "B.Fab")
		)
		(pad "1" smd custom
			(at 0 -0.762)
			(size 0.2159 0.2159)
			(layers "B.Cu" "B.Mask" "B.Paste")
			(net "P1V53_STBY")
			(options
				(clearance outline)
				(anchor circle)
			)
			(primitives
				(gr_poly
					(pts
						(arc
							(start -0.3302 0.4318)
							(mid -0.402042 0.402042)
							(end -0.4318 0.3302)
						)
						(arc
							(start -0.4318 -0.3302)
							(mid -0.402042 -0.402042)
							(end -0.3302 -0.4318)
						)
						(arc
							(start 0.3302 -0.4318)
							(mid 0.402042 -0.402042)
							(end 0.4318 -0.3302)
						)
						(arc
							(start 0.4318 0.3302)
							(mid 0.402042 0.402042)
							(end 0.3302 0.4318)
						)
					)
					(width 0)
					(fill yes)
				)
			)
		)
		(pad "2" smd custom
			(at 0 0.762)
			(size 0.2159 0.2159)
			(layers "B.Cu" "B.Mask" "B.Paste")
			(net "GND")
			(options
				(clearance outline)
				(anchor circle)
			)
			(primitives
				(gr_poly
					(pts
						(arc
							(start -0.3302 0.4318)
							(mid -0.402042 0.402042)
							(end -0.4318 0.3302)
						)
						(arc
							(start -0.4318 -0.3302)
							(mid -0.402042 -0.402042)
							(end -0.3302 -0.4318)
						)
						(arc
							(start 0.3302 -0.4318)
							(mid 0.402042 -0.402042)
							(end 0.4318 -0.3302)
						)
						(arc
							(start 0.4318 0.3302)
							(mid 0.402042 0.402042)
							(end 0.3302 0.4318)
						)
					)
					(width 0)
					(fill yes)
				)
			)
		)
	)
	(footprint ""
		(layer "B.Cu")
		(at 124.403612 -211.328 90)
		(property "Reference" "SC1291"
			(at 0 0 90)
			(layer "B.SilkS")
			(hide yes)
			(effects
				(font
					(size 1.27 1.27)
				)
				(justify mirror)
			)
		)
		(property "Value" "SCD1U16V2KX-3GP"
			(at -1.1811 -2.7051 90)
			(unlocked yes)
			(layer "B.Fab")
			(hide yes)
			(effects
				(font
					(size 1.016 1.016)
					(thickness 0.1524)
				)
				(justify mirror)
			)
		)
		(property "Device Type" "C402H22"
			(at -1.1811 -4.2291 90)
			(unlocked yes)
			(layer "B.Fab")
			(hide yes)
			(effects
				(font
					(size 1.016 1.016)
					(thickness 0.1524)
				)
				(justify mirror)
			)
		)
		(duplicate_pad_numbers_are_jumpers no)
		(fp_rect
			(start 0.4318 0.9525)
			(end -0.4318 -0.9525)
			(stroke
				(width 0)
				(type default)
			)
			(fill no)
			(layer "B.CrtYd")
		)
		(fp_rect
			(start 0.4318 0.9525)
			(end -0.4318 -0.9525)
			(stroke
				(width 0)
				(type default)
			)
			(fill no)
			(layer "B.Fab")
		)
		(pad "1" smd custom
			(at 0 -0.4445 270)
			(size 0.1524 0.1524)
			(layers "B.Cu" "B.Mask" "B.Paste")
			(net "1.2V_REDV")
			(options
				(clearance outline)
				(anchor circle)
			)
			(primitives
				(gr_poly
					(pts
						(arc
							(start 0.3048 0.2032)
							(mid 0.275042 0.275042)
							(end 0.2032 0.3048)
						)
						(arc
							(start -0.2032 0.3048)
							(mid -0.275042 0.275042)
							(end -0.3048 0.2032)
						)
						(arc
							(start -0.3048 -0.2032)
							(mid -0.275042 -0.275042)
							(end -0.2032 -0.3048)
						)
						(arc
							(start 0.2032 -0.3048)
							(mid 0.275042 -0.275042)
							(end 0.3048 -0.2032)
						)
					)
					(width 0)
					(fill yes)
				)
			)
		)
		(pad "2" smd custom
			(at 0 0.4445 270)
			(size 0.1524 0.1524)
			(layers "B.Cu" "B.Mask" "B.Paste")
			(net "GND")
			(options
				(clearance outline)
				(anchor circle)
			)
			(primitives
				(gr_poly
					(pts
						(arc
							(start 0.3048 0.2032)
							(mid 0.275042 0.275042)
							(end 0.2032 0.3048)
						)
						(arc
							(start -0.2032 0.3048)
							(mid -0.275042 0.275042)
							(end -0.3048 0.2032)
						)
						(arc
							(start -0.3048 -0.2032)
							(mid -0.275042 -0.275042)
							(end -0.2032 -0.3048)
						)
						(arc
							(start 0.2032 -0.3048)
							(mid 0.275042 -0.275042)
							(end 0.3048 -0.2032)
						)
					)
					(width 0)
					(fill yes)
				)
			)
		)
	)
	(footprint ""
		(layer "B.Cu")
		(at 102.997 -225.933 -90)
		(property "Reference" "R666"
			(at 0 0 90)
			(layer "B.SilkS")
			(hide yes)
			(effects
				(font
					(size 1.27 1.27)
				)
				(justify mirror)
			)
		)
		(property "Value" "0R2J-2-GP"
			(at -0.064008 -3.993896 270)
			(unlocked yes)
			(layer "B.Fab")
			(hide yes)
			(effects
				(font
					(size 1.016 1.016)
					(thickness 0.1524)
				)
				(justify mirror)
			)
		)
		(property "Device Type" "R402H16"
			(at -0.064008 -5.517896 270)
			(unlocked yes)
			(layer "B.Fab")
			(hide yes)
			(effects
				(font
					(size 1.016 1.016)
					(thickness 0.1524)
				)
				(justify mirror)
			)
		)
		(duplicate_pad_numbers_are_jumpers no)
		(fp_line
			(start -0.508 -0.9398)
			(end 0.508 -0.9398)
			(stroke
				(width 0.1524)
				(type default)
			)
			(layer "B.SilkS")
		)
		(fp_line
			(start 0.508 -0.9398)
			(end 0.508 0.9398)
			(stroke
				(width 0.1524)
				(type default)
			)
			(layer "B.SilkS")
		)
		(fp_rect
			(start 0.508 0.9398)
			(end -0.508 -0.9398)
			(stroke
				(width 0)
				(type default)
			)
			(fill no)
			(layer "B.CrtYd")
		)
		(fp_rect
			(start 0.508 0.9398)
			(end -0.508 -0.9398)
			(stroke
				(width 0)
				(type default)
			)
			(fill no)
			(layer "B.Fab")
		)
		(pad "1" smd custom
			(at 0 -0.4445 90)
			(size 0.1397 0.1397)
			(layers "B.Cu" "B.Mask" "B.Paste")
			(net "SAS_FAULT_LED1")
			(options
				(clearance outline)
				(anchor circle)
			)
			(primitives
				(gr_poly
					(pts
						(arc
							(start -0.1778 0.2794)
							(mid -0.249642 0.249642)
							(end -0.2794 0.1778)
						)
						(arc
							(start -0.2794 -0.1778)
							(mid -0.249642 -0.249642)
							(end -0.1778 -0.2794)
						)
						(arc
							(start 0.1778 -0.2794)
							(mid 0.249642 -0.249642)
							(end 0.2794 -0.1778)
						)
						(arc
							(start 0.2794 0.1778)
							(mid 0.249642 0.249642)
							(end 0.1778 0.2794)
						)
					)
					(width 0)
					(fill yes)
				)
			)
		)
		(pad "2" smd custom
			(at 0 0.4445 90)
			(size 0.1397 0.1397)
			(layers "B.Cu" "B.Mask" "B.Paste")
			(net "SAS_HDD_LED_1")
			(options
				(clearance outline)
				(anchor circle)
			)
			(primitives
				(gr_poly
					(pts
						(arc
							(start -0.1778 0.2794)
							(mid -0.249642 0.249642)
							(end -0.2794 0.1778)
						)
						(arc
							(start -0.2794 -0.1778)
							(mid -0.249642 -0.249642)
							(end -0.1778 -0.2794)
						)
						(arc
							(start 0.1778 -0.2794)
							(mid 0.249642 -0.249642)
							(end 0.2794 -0.1778)
						)
						(arc
							(start 0.2794 0.1778)
							(mid 0.249642 0.249642)
							(end 0.1778 0.2794)
						)
					)
					(width 0)
					(fill yes)
				)
			)
		)
	)
)
